# S9S_MB_2U (Grand Teton) — schematic netlist excerpt (pin names and nets, part order shuffled) for the footprints in the layout excerpt that follows; sources: Cadence DE-HDL packaged netlist, KiCad conversion of 03242023_DA0F0TMBIJ0_F0T_Motherboard_J_brd_V01_OCP.brd

J29  SCONN288_ADR50017P130CC  SCONN288_ADR50017-P130CC IO  pkg DDR288S_1-1VXB  page 110
  VIN_BULK0  = P12V_S3_AUX_CPU1_NVDIMM
  RFU0  = TP_CHG_CPU1_DIMM1_FRU_0
  VIN_MGMT  = P3V3_AUX
  HSCL  = I3C_SPD_DDREFGH_CPU1_LVC1_SCL_4
  HSDA  = I3C_SPD_DDREFGH_CPU1_LVC1_SDA
  VSS0  = GND
  DQ0_A  = M_G_CPU1_SA_DQ<0>
  VSS1  = GND
  DQ1_A  = M_G_CPU1_SA_DQ<1>
  VSS2  = GND
  DQS0_A_T  = M_G_CPU1_SA_DQS_DP<0>
  DQS0_A_C  = M_G_CPU1_SA_DQS_DN<0>
  VSS3  = GND
  DQ4_A  = M_G_CPU1_SA_DQ<4>
  VSS4  = GND
  DQ5_A  = M_G_CPU1_SA_DQ<5>
  VSS5  = GND
  DQ8_A  = M_G_CPU1_SA_DQ<8>
  VSS6  = GND
  DQ9_A  = M_G_CPU1_SA_DQ<9>
  VSS7  = GND
  DQS1_A_T  = M_G_CPU1_SA_DQS_DP<1>
  DQS1_A_C  = M_G_CPU1_SA_DQS_DN<1>
  VSS8  = GND
  DQ12_A  = M_G_CPU1_SA_DQ<12>
  VSS9  = GND
  DQ13_A  = M_G_CPU1_SA_DQ<13>
  VSS10  = GND
  DQ16_A  = M_G_CPU1_SA_DQ<16>
  VSS11  = GND
  DQ17_A  = M_G_CPU1_SA_DQ<17>
  VSS12  = GND
  DQS2_A_T  = M_G_CPU1_SA_DQS_DP<2>
  DQS2_A_C  = M_G_CPU1_SA_DQS_DN<2>
  VSS13  = GND
  DQ20_A  = M_G_CPU1_SA_DQ<20>
  VSS14  = GND
  DQ21_A  = M_G_CPU1_SA_DQ<21>
  VSS15  = GND
  DQ24_A  = M_G_CPU1_SA_DQ<24>
  VSS16  = GND
  DQ25_A  = M_G_CPU1_SA_DQ<25>
  VSS17  = GND
  DQS3_A_T  = M_G_CPU1_SA_DQS_DP<3>
  DQS3_A_C  = M_G_CPU1_SA_DQS_DN<3>
  VSS18  = GND
  DQ28_A  = M_G_CPU1_SA_DQ<28>
  VSS19  = GND
  DQ29_A  = M_G_CPU1_SA_DQ<29>
  VSS20  = GND
  CB0_A  = M_G_CPU1_SA_CB<0>
  VSS21  = GND
  CB1_A  = M_G_CPU1_SA_CB<1>
  VSS22  = GND
  DQS4_A_T  = M_G_CPU1_SA_DQS_DP<4>
  DQS4_A_C  = M_G_CPU1_SA_DQS_DN<4>
  VSS23  = GND
  CB4_A  = M_G_CPU1_SA_CB<4>
  VSS24  = GND
  CB5_A  = M_G_CPU1_SA_CB<5>
  VSS25  = GND
  ALERT_N  = M_G_CPU1_ALERT_N
  VSS26  = GND
  CS0_A_N  = M_G_CPU1_SA_CS_N<0>
  VSS27  = GND
  CA0_A  = M_G_CPU1_SA_CA<0>
  VSS28  = GND
  CA2_A  = M_G_CPU1_SA_CA<2>
  VSS29  = GND
  CA4_A  = M_G_CPU1_SA_CA<4>
  VSS30  = GND
  CA6_A  = M_G_CPU1_SA_CA<6>
  VSS31  = GND
  PAR_A  = M_G_CPU1_SA_PAR
  VSS32  = GND
  CA0_B  = M_G_CPU1_SB_CA<0>
  VSS33  = GND
  CA2_B  = M_G_CPU1_SB_CA<2>
  VSS34  = GND
  CA4_B  = M_G_CPU1_SB_CA<4>
  VSS35  = GND
  CA6_B  = M_G_CPU1_SB_CA<6>
  VSS36  = GND
  CS0_B_N  = M_G_CPU1_SB_CS_N<0>
  VSS37  = GND
  \lbd||rsp_a_n\  = M_G_CPU1_SA_RSP<0>
  \lbs||rsp_b_n\  = M_G_CPU1_SB_RSP<0>
  VSS38  = GND
  CB4_B  = M_G_CPU1_SB_CB<4>
  VSS39  = GND
  CB5_B  = M_G_CPU1_SB_CB<5>
  VSS40  = GND
  \dqs9_b_t||tdqs9_b_t||dbi4_b_n\  = M_G_CPU1_SB_DQS_DP<9>
  \dqs9_b_c||tdqs9_b_c\  = M_G_CPU1_SB_DQS_DN<9>
  VSS41  = GND
  CB0_B  = M_G_CPU1_SB_CB<0>
  VSS42  = GND
  CB1_B  = M_G_CPU1_SB_CB<1>
  VSS43  = GND
  DQ0_B  = M_G_CPU1_SB_DQ<0>
  VSS44  = GND
  DQ1_B  = M_G_CPU1_SB_DQ<1>
  VSS45  = GND
  DQS0_B_T  = M_G_CPU1_SB_DQS_DP<0>
  DQS0_B_C  = M_G_CPU1_SB_DQS_DN<0>
  VSS46  = GND
  DQ4_B  = M_G_CPU1_SB_DQ<4>
  VSS47  = GND
  DQ5_B  = M_G_CPU1_SB_DQ<5>
  VSS48  = GND
  DQ8_B  = M_G_CPU1_SB_DQ<8>
  VSS49  = GND
  DQ9_B  = M_G_CPU1_SB_DQ<9>
  VSS50  = GND
  DQS1_B_T  = M_G_CPU1_SB_DQS_DP<1>
  DQS1_B_C  = M_G_CPU1_SB_DQS_DN<1>
  VSS51  = GND
  DQ12_B  = M_G_CPU1_SB_DQ<12>
  VSS52  = GND
  DQ13_B  = M_G_CPU1_SB_DQ<13>
  VSS53  = GND
  DQ16_B  = M_G_CPU1_SB_DQ<16>
  VSS54  = GND
  DQ17_B  = M_G_CPU1_SB_DQ<17>
  VSS55  = GND
  DQS2_B_T  = M_G_CPU1_SB_DQS_DP<2>
  DQS2_B_C  = M_G_CPU1_SB_DQS_DN<2>
  VSS56  = GND
  DQ20_B  = M_G_CPU1_SB_DQ<20>
  VSS57  = GND
  DQ21_B  = M_G_CPU1_SB_DQ<21>
  VSS58  = GND
  DQ24_B  = M_G_CPU1_SB_DQ<24>
  VSS59  = GND
  DQ25_B  = M_G_CPU1_SB_DQ<25>
  VSS60  = GND
  DQS3_B_T  = M_G_CPU1_SB_DQS_DP<3>
  DQS3_B_C  = M_G_CPU1_SB_DQS_DN<3>
  VSS61  = GND
  DQ28_B  = M_G_CPU1_SB_DQ<28>
  VSS62  = GND
  DQ29_B  = M_G_CPU1_SB_DQ<29>
  VSS63  = GND
  RFU1  = TP_CHG_CPU1_DIMM1_FRU_1
  VIN_BULK1  = P12V_S3_AUX_CPU1_NVDIMM
  VIN_BULK2  = P12V_S3_AUX_CPU1_NVDIMM
  \pwr_good||fail_n\  = PWRGD_CHG_CPU1_DIMM1
  HSA  = PD_CHG_CPU1_DIMM1_SAA
  RFU2  = TP_CHG_CPU1_DIMM1_FRU_2
  RFU3  = TP_CHG_CPU1_DIMM1_FRU_3
  VSS64  = GND
  DQ2_A  = M_G_CPU1_SA_DQ<2>
  VSS65  = GND
  DQ3_A  = M_G_CPU1_SA_DQ<3>
  VSS66  = GND
  \dqs5_a_c||tdqs5_a_c||dqs5_a_t||tdqs5_a_t\  = M_G_CPU1_SA_DQS_DN<5>
  \dqs5_a_t||tdqs5_a_t\  = M_G_CPU1_SA_DQS_DP<5>
  VSS67  = GND
  DQ6_A  = M_G_CPU1_SA_DQ<6>
  VSS68  = GND
  DQ7_A  = M_G_CPU1_SA_DQ<7>
  VSS69  = GND
  DQ10_A  = M_G_CPU1_SA_DQ<10>
  VSS70  = GND
  DQ11_A  = M_G_CPU1_SA_DQ<11>
  VSS71  = GND
  \dqs6_a_c||tdqs6_a_c||dqs6_a_t||tdqs6_a_t\  = M_G_CPU1_SA_DQS_DN<6>
  \dqs6_a_t||tdqs6_a_t\  = M_G_CPU1_SA_DQS_DP<6>
  VSS72  = GND
  DQ14_A  = M_G_CPU1_SA_DQ<14>
  VSS73  = GND
  DQ15_A  = M_G_CPU1_SA_DQ<15>
  VSS74  = GND
  DQ18_A  = M_G_CPU1_SA_DQ<18>
  VSS75  = GND
  DQ19_A  = M_G_CPU1_SA_DQ<19>
  VSS76  = GND
  \dqs7_a_c||tdqs7_a_c\  = M_G_CPU1_SA_DQS_DN<7>
  \dqs7_a_t||tdqs7_a_t\  = M_G_CPU1_SA_DQS_DP<7>
  VSS77  = GND
  DQ22_A  = M_G_CPU1_SA_DQ<22>
  VSS78  = GND
  DQ23_A  = M_G_CPU1_SA_DQ<23>
  VSS79  = GND
  DQ26_A  = M_G_CPU1_SA_DQ<26>
  VSS80  = GND
  DQ27_A  = M_G_CPU1_SA_DQ<27>
  VSS81  = GND
  \dqs8_a_c||tdqs8_a_c\  = M_G_CPU1_SA_DQS_DN<8>
  \dqs8_a_t||tdqs8_a_t\  = M_G_CPU1_SA_DQS_DP<8>
  VSS82  = GND
  DQ30_A  = M_G_CPU1_SA_DQ<30>
  VSS83  = GND
  DQ31_A  = M_G_CPU1_SA_DQ<31>
  VSS84  = GND
  CB2_A  = M_G_CPU1_SA_CB<2>
  VSS85  = GND
  CB3_A  = M_G_CPU1_SA_CB<3>
  VSS86  = GND
  \dqs9_a_c||tdqs9_a_c\  = M_G_CPU1_SA_DQS_DN<9>
  \dqs9_a_t||tdqs9_a_t\  = M_G_CPU1_SA_DQS_DP<9>
  VSS87  = GND
  CB6_A  = M_G_CPU1_SA_CB<6>
  VSS88  = GND
  CB7_A  = M_G_CPU1_SA_CB<7>
  VSS89  = GND
  RESET_N  = RST_M_GH_CPU1_FPGA_N
  VSS90  = GND
  CS1_A_N  = M_G_CPU1_SA_CS_N<1>
  VSS91  = GND
  CA1_A  = M_G_CPU1_SA_CA<1>
  VSS92  = GND
  CA3_A  = M_G_CPU1_SA_CA<3>
  VSS93  = GND
  CA5_A  = M_G_CPU1_SA_CA<5>
  VSS94  = GND
  CK_T  = M_G_CPU1_CLK_DP<0>
  CK_C  = M_G_CPU1_CLK_DN<0>
  VSS95  = GND
  RFU4  = TP_CHG_CPU1_DIMM1_FRU_4
  CA1_B  = M_G_CPU1_SB_CA<1>
  VSS96  = GND
  CA3_B  = M_G_CPU1_SB_CA<3>
  VSS97  = GND
  CA5_B  = M_G_CPU1_SB_CA<5>
  VSS98  = GND
  PAR_B  = M_G_CPU1_SB_PAR
  VSS99  = GND
  CS1_B_N  = M_G_CPU1_SB_CS_N<1>
  VSS100  = GND
  RFU5  = TP_CHG_CPU1_DIMM1_FRU_5
  RFU6  = TP_CHG_CPU1_DIMM1_FRU_6
  VSS101  = GND
  CB6_B  = M_G_CPU1_SB_CB<6>
  VSS102  = GND
  CB7_B  = M_G_CPU1_SB_CB<7>
  VSS103  = GND
  DQS4_B_C  = M_G_CPU1_SB_DQS_DN<4>
  DQS4_B_T  = M_G_CPU1_SB_DQS_DP<4>
  VSS104  = GND
  CB2_B  = M_G_CPU1_SB_CB<2>
  VSS105  = GND
  CB3_B  = M_G_CPU1_SB_CB<3>
  VSS106  = GND
  DQ2_B  = M_G_CPU1_SB_DQ<2>
  VSS107  = GND
  DQ3_B  = M_G_CPU1_SB_DQ<3>
  VSS108  = GND
  \dqs5_b_c||tdqs5_b_c\  = M_G_CPU1_SB_DQS_DN<5>
  \dqs5_b_t||tdqs5_b_t\  = M_G_CPU1_SB_DQS_DP<5>
  VSS109  = GND
  DQ6_B  = M_G_CPU1_SB_DQ<6>
  VSS110  = GND
  DQ7_B  = M_G_CPU1_SB_DQ<7>
  VSS111  = GND
  DQ10_B  = M_G_CPU1_SB_DQ<10>
  VSS112  = GND
  DQ11_B  = M_G_CPU1_SB_DQ<11>
  VSS113  = GND
  \dqs6_b_c||tdqs6_b_c\  = M_G_CPU1_SB_DQS_DN<6>
  \dqs6_b_t||tdqs6_b_t\  = M_G_CPU1_SB_DQS_DP<6>
  VSS114  = GND
  DQ14_B  = M_G_CPU1_SB_DQ<14>
  VSS115  = GND
  DQ15_B  = M_G_CPU1_SB_DQ<15>
  VSS116  = GND
  DQ18_B  = M_G_CPU1_SB_DQ<18>
  VSS117  = GND
  DQ19_B  = M_G_CPU1_SB_DQ<19>
  VSS118  = GND
  \dqs7_b_c||tdqs7_b_c\  = M_G_CPU1_SB_DQS_DN<7>
  \dqs7_b_t||tdqs7_b_t\  = M_G_CPU1_SB_DQS_DP<7>
  VSS119  = GND
  DQ22_B  = M_G_CPU1_SB_DQ<22>
  VSS120  = GND
  DQ23_B  = M_G_CPU1_SB_DQ<23>
  VSS121  = GND
  DQ26_B  = M_G_CPU1_SB_DQ<26>
  VSS122  = GND
  DQ27_B  = M_G_CPU1_SB_DQ<27>
  VSS123  = GND
  \dqs8_b_c||tdqs8_b_c\  = M_G_CPU1_SB_DQS_DN<8>
  \dqs8_b_t||tdqs8_b_t\  = M_G_CPU1_SB_DQS_DP<8>
  VSS124  = GND
  DQ30_B  = M_G_CPU1_SB_DQ<30>
  VSS125  = GND
  DQ31_B  = M_G_CPU1_SB_DQ<31>
  VSS126  = GND
  G1  = GND
  G2  = GND
  G3  = GND

(kicad_pcb
	(version 20260206)
	(generator "pcbnew")
	(generator_version "10.0")
	(general
		(thickness 1.6)
		(legacy_teardrops no)
	)
	(paper "A4")
	(title_block
		(title "03242023_DA0F0TMBIJ0_F0T_Motherboard_J_brd_V01_OCP.brd")
		(comment 1 "Grand Teton / footprint 2874 of 6105 (J29), pads 92-137 of 291")
	)
	(layers
		(0 "F.Cu" signal "TOP")
		(4 "In1.Cu" signal "GND")
		(6 "In2.Cu" signal "IN1")
		(8 "In3.Cu" signal "GND1")
		(10 "In4.Cu" signal "IN2")
		(12 "In5.Cu" signal "GND2")
		(14 "In6.Cu" signal "IN3")
		(16 "In7.Cu" signal "GND3")
		(18 "In8.Cu" signal "VCC")
		(20 "In9.Cu" signal "VCC1")
		(22 "In10.Cu" signal "GND4")
		(24 "In11.Cu" signal "IN4")
		(26 "In12.Cu" signal "GND5")
		(28 "In13.Cu" signal "IN5")
		(30 "In14.Cu" signal "GND6")
		(32 "In15.Cu" signal "IN6")
		(34 "In16.Cu" signal "GND7")
		(2 "B.Cu" signal "BOTTOM")
		(9 "F.Adhes" user "F.Adhesive")
		(11 "B.Adhes" user "B.Adhesive")
		(13 "F.Paste" user "Package Geometry/Pastemask Top")
		(15 "B.Paste" user "Package Geometry/Pastemask Bottom")
		(5 "F.SilkS" user "Ref Des/Silkscreen Top")
		(7 "B.SilkS" user "Ref Des/Silkscreen Bottom")
		(1 "F.Mask" user "Board Geometry/Soldermask Top")
		(3 "B.Mask" user "Board Geometry/Soldermask Bottom")
		(17 "Dwgs.User" user "User.Drawings")
		(19 "Cmts.User" user "User.Comments")
		(21 "Eco1.User" user "User.Eco1")
		(23 "Eco2.User" user "User.Eco2")
		(25 "Edge.Cuts" user "Board Geometry/Outline")
		(27 "Margin" user)
		(31 "F.CrtYd" user "Package Geometry/Place Bound Top")
		(29 "B.CrtYd" user "Package Geometry/Place Bound Bottom")
		(35 "F.Fab" user "Ref Des/Assembly Top")
		(33 "B.Fab" user "Ref Des/Assembly Bottom")
	)
	(footprint ""
		(layer "F.Cu")
		(at 198.58228 -258.091686)
		(property "Reference" "J29"
			(at -3.683 -81.702148 0)
			(unlocked yes)
			(layer "F.SilkS")
			(effects
				(font
					(size 0.7874 0.5842)
					(thickness 0.1524)
				)
				(justify left)
			)
		)
		(property "Value" ""
			(at 0 0 0)
			(layer "F.Fab")
			(effects
				(font
					(size 1.27 1.27)
				)
			)
		)
		(duplicate_pad_numbers_are_jumpers no)
		(pad "92" smd rect
			(at -2.050034 19.12493 270)
			(size 0.519938 1.4986)
			(layers "F.Cu" "F.Mask" "F.Paste")
			(net "GND")
		)
		(pad "93" smd rect
			(at -2.050034 19.975068 270)
			(size 0.519938 1.4986)
			(layers "F.Cu" "F.Mask" "F.Paste")
			(net "M_G_CPU1_SB_DQS_DP<9>")
		)
		(pad "94" smd rect
			(at -2.050034 20.824952 270)
			(size 0.519938 1.4986)
			(layers "F.Cu" "F.Mask" "F.Paste")
			(net "M_G_CPU1_SB_DQS_DN<9>")
		)
		(pad "95" smd rect
			(at -2.050034 21.67509 270)
			(size 0.519938 1.4986)
			(layers "F.Cu" "F.Mask" "F.Paste")
			(net "GND")
		)
		(pad "96" smd rect
			(at -2.050034 22.524974 270)
			(size 0.519938 1.4986)
			(layers "F.Cu" "F.Mask" "F.Paste")
			(net "M_G_CPU1_SB_CB<0>")
		)
		(pad "97" smd rect
			(at -2.050034 23.375112 270)
			(size 0.519938 1.4986)
			(layers "F.Cu" "F.Mask" "F.Paste")
			(net "GND")
		)
		(pad "98" smd rect
			(at -2.050034 24.224996 270)
			(size 0.519938 1.4986)
			(layers "F.Cu" "F.Mask" "F.Paste")
			(net "M_G_CPU1_SB_CB<1>")
		)
		(pad "99" smd rect
			(at -2.050034 25.07488 270)
			(size 0.519938 1.4986)
			(layers "F.Cu" "F.Mask" "F.Paste")
			(net "GND")
		)
		(pad "100" smd rect
			(at -2.050034 25.925018 270)
			(size 0.519938 1.4986)
			(layers "F.Cu" "F.Mask" "F.Paste")
			(net "M_G_CPU1_SB_DQ<0>")
		)
		(pad "101" smd rect
			(at -2.050034 26.774902 270)
			(size 0.519938 1.4986)
			(layers "F.Cu" "F.Mask" "F.Paste")
			(net "GND")
		)
		(pad "102" smd rect
			(at -2.050034 27.62504 270)
			(size 0.519938 1.4986)
			(layers "F.Cu" "F.Mask" "F.Paste")
			(net "M_G_CPU1_SB_DQ<1>")
		)
		(pad "103" smd rect
			(at -2.050034 28.474924 270)
			(size 0.519938 1.4986)
			(layers "F.Cu" "F.Mask" "F.Paste")
			(net "GND")
		)
		(pad "104" smd rect
			(at -2.050034 29.325062 270)
			(size 0.519938 1.4986)
			(layers "F.Cu" "F.Mask" "F.Paste")
			(net "M_G_CPU1_SB_DQS_DP<0>")
		)
		(pad "105" smd rect
			(at -2.050034 30.174946 270)
			(size 0.519938 1.4986)
			(layers "F.Cu" "F.Mask" "F.Paste")
			(net "M_G_CPU1_SB_DQS_DN<0>")
		)
		(pad "106" smd rect
			(at -2.050034 31.025084 270)
			(size 0.519938 1.4986)
			(layers "F.Cu" "F.Mask" "F.Paste")
			(net "GND")
		)
		(pad "107" smd rect
			(at -2.050034 31.874968 270)
			(size 0.519938 1.4986)
			(layers "F.Cu" "F.Mask" "F.Paste")
			(net "M_G_CPU1_SB_DQ<4>")
		)
		(pad "108" smd rect
			(at -2.050034 32.725106 270)
			(size 0.519938 1.4986)
			(layers "F.Cu" "F.Mask" "F.Paste")
			(net "GND")
		)
		(pad "109" smd rect
			(at -2.050034 33.57499 270)
			(size 0.519938 1.4986)
			(layers "F.Cu" "F.Mask" "F.Paste")
			(net "M_G_CPU1_SB_DQ<5>")
		)
		(pad "110" smd rect
			(at -2.050034 34.425128 270)
			(size 0.519938 1.4986)
			(layers "F.Cu" "F.Mask" "F.Paste")
			(net "GND")
		)
		(pad "111" smd rect
			(at -2.050034 35.275012 270)
			(size 0.519938 1.4986)
			(layers "F.Cu" "F.Mask" "F.Paste")
			(net "M_G_CPU1_SB_DQ<8>")
		)
		(pad "112" smd rect
			(at -2.050034 36.124896 270)
			(size 0.519938 1.4986)
			(layers "F.Cu" "F.Mask" "F.Paste")
			(net "GND")
		)
		(pad "113" smd rect
			(at -2.050034 36.975034 270)
			(size 0.519938 1.4986)
			(layers "F.Cu" "F.Mask" "F.Paste")
			(net "M_G_CPU1_SB_DQ<9>")
		)
		(pad "114" smd rect
			(at -2.050034 37.824918 270)
			(size 0.519938 1.4986)
			(layers "F.Cu" "F.Mask" "F.Paste")
			(net "GND")
		)
		(pad "115" smd rect
			(at -2.050034 38.675056 270)
			(size 0.519938 1.4986)
			(layers "F.Cu" "F.Mask" "F.Paste")
			(net "M_G_CPU1_SB_DQS_DP<1>")
		)
		(pad "116" smd rect
			(at -2.050034 39.52494 270)
			(size 0.519938 1.4986)
			(layers "F.Cu" "F.Mask" "F.Paste")
			(net "M_G_CPU1_SB_DQS_DN<1>")
		)
		(pad "117" smd rect
			(at -2.050034 40.375078 270)
			(size 0.519938 1.4986)
			(layers "F.Cu" "F.Mask" "F.Paste")
			(net "GND")
		)
		(pad "118" smd rect
			(at -2.050034 41.224962 270)
			(size 0.519938 1.4986)
			(layers "F.Cu" "F.Mask" "F.Paste")
			(net "M_G_CPU1_SB_DQ<12>")
		)
		(pad "119" smd rect
			(at -2.050034 42.0751 270)
			(size 0.519938 1.4986)
			(layers "F.Cu" "F.Mask" "F.Paste")
			(net "GND")
		)
		(pad "120" smd rect
			(at -2.050034 42.924984 270)
			(size 0.519938 1.4986)
			(layers "F.Cu" "F.Mask" "F.Paste")
			(net "M_G_CPU1_SB_DQ<13>")
		)
		(pad "121" smd rect
			(at -2.050034 43.775122 270)
			(size 0.519938 1.4986)
			(layers "F.Cu" "F.Mask" "F.Paste")
			(net "GND")
		)
		(pad "122" smd rect
			(at -2.050034 44.625006 270)
			(size 0.519938 1.4986)
			(layers "F.Cu" "F.Mask" "F.Paste")
			(net "M_G_CPU1_SB_DQ<16>")
		)
		(pad "123" smd rect
			(at -2.050034 45.47489 270)
			(size 0.519938 1.4986)
			(layers "F.Cu" "F.Mask" "F.Paste")
			(net "GND")
		)
		(pad "124" smd rect
			(at -2.050034 46.325028 270)
			(size 0.519938 1.4986)
			(layers "F.Cu" "F.Mask" "F.Paste")
			(net "M_G_CPU1_SB_DQ<17>")
		)
		(pad "125" smd rect
			(at -2.050034 47.174912 270)
			(size 0.519938 1.4986)
			(layers "F.Cu" "F.Mask" "F.Paste")
			(net "GND")
		)
		(pad "126" smd rect
			(at -2.050034 48.02505 270)
			(size 0.519938 1.4986)
			(layers "F.Cu" "F.Mask" "F.Paste")
			(net "M_G_CPU1_SB_DQS_DP<2>")
		)
		(pad "127" smd rect
			(at -2.050034 48.874934 270)
			(size 0.519938 1.4986)
			(layers "F.Cu" "F.Mask" "F.Paste")
			(net "M_G_CPU1_SB_DQS_DN<2>")
		)
		(pad "128" smd rect
			(at -2.050034 49.725072 270)
			(size 0.519938 1.4986)
			(layers "F.Cu" "F.Mask" "F.Paste")
			(net "GND")
		)
		(pad "129" smd rect
			(at -2.050034 50.574956 270)
			(size 0.519938 1.4986)
			(layers "F.Cu" "F.Mask" "F.Paste")
			(net "M_G_CPU1_SB_DQ<20>")
		)
		(pad "130" smd rect
			(at -2.050034 51.425094 270)
			(size 0.519938 1.4986)
			(layers "F.Cu" "F.Mask" "F.Paste")
			(net "GND")
		)
		(pad "131" smd rect
			(at -2.050034 52.274978 270)
			(size 0.519938 1.4986)
			(layers "F.Cu" "F.Mask" "F.Paste")
			(net "M_G_CPU1_SB_DQ<21>")
		)
		(pad "132" smd rect
			(at -2.050034 53.125116 270)
			(size 0.519938 1.4986)
			(layers "F.Cu" "F.Mask" "F.Paste")
			(net "GND")
		)
		(pad "133" smd rect
			(at -2.050034 53.975 270)
			(size 0.519938 1.4986)
			(layers "F.Cu" "F.Mask" "F.Paste")
			(net "M_G_CPU1_SB_DQ<24>")
		)
		(pad "134" smd rect
			(at -2.050034 54.824884 270)
			(size 0.519938 1.4986)
			(layers "F.Cu" "F.Mask" "F.Paste")
			(net "GND")
		)
		(pad "135" smd rect
			(at -2.050034 55.675022 270)
			(size 0.519938 1.4986)
			(layers "F.Cu" "F.Mask" "F.Paste")
			(net "M_G_CPU1_SB_DQ<25>")
		)
		(pad "136" smd rect
			(at -2.050034 56.524906 270)
			(size 0.519938 1.4986)
			(layers "F.Cu" "F.Mask" "F.Paste")
			(net "GND")
		)
		(pad "137" smd rect
			(at -2.050034 57.375044 270)
			(size 0.519938 1.4986)
			(layers "F.Cu" "F.Mask" "F.Paste")
			(net "M_G_CPU1_SB_DQS_DP<3>")
		)
	)
)
